(kicad_pcb
	(version 20260206)
	(generator "pcbnew")
	(generator_version "10.0")
	(general
		(thickness 1.6)
		(legacy_teardrops no)
	)
	(paper "A4")
	(title_block
		(title "baseboard — 13948-1b.1110WZS1818.brd")
		(comment 1 "Honey Badger (Wiwynn) / footprint 1534 of 2523 (CN8), pads 1-75 of 166")
	)
	(layers
		(0 "F.Cu" signal "TOP")
		(4 "In1.Cu" signal "L2GND")
		(6 "In2.Cu" signal "L3")
		(8 "In3.Cu" signal "L4VCC")
		(10 "In4.Cu" signal "L5VCC")
		(12 "In5.Cu" signal "L6")
		(14 "In6.Cu" signal "L7GND")
		(2 "B.Cu" signal "BOTTOM")
		(9 "F.Adhes" user "F.Adhesive")
		(11 "B.Adhes" user "B.Adhesive")
		(13 "F.Paste" user "Package Geometry/Pastemask Top")
		(15 "B.Paste" user "Package Geometry/Pastemask Bottom")
		(5 "F.SilkS" user "Ref Des/Silkscreen Top")
		(7 "B.SilkS" user "Ref Des/Silkscreen Bottom")
		(1 "F.Mask" user "Board Geometry/Soldermask Top")
		(3 "B.Mask" user "Board Geometry/Soldermask Bottom")
		(17 "Dwgs.User" user "User.Drawings")
		(19 "Cmts.User" user "User.Comments")
		(21 "Eco1.User" user "User.Eco1")
		(23 "Eco2.User" user "User.Eco2")
		(25 "Edge.Cuts" user "Board Geometry/Outline")
		(27 "Margin" user)
		(31 "F.CrtYd" user "Package Geometry/Place Bound Top")
		(29 "B.CrtYd" user "Package Geometry/Place Bound Bottom")
		(35 "F.Fab" user "Ref Des/Assembly Top")
		(33 "B.Fab" user "Ref Des/Assembly Bottom")
	)
	(footprint ""
		(layer "F.Cu")
		(at 209.799936 -77.0001 180)
		(property "Reference" "CN8"
			(at 0 0 180)
			(layer "F.SilkS")
			(hide yes)
			(effects
				(font
					(size 1.27 1.27)
				)
			)
		)
		(property "Value" "PCISLT164-44-GP"
			(at -23.3172 -6.8961 180)
			(unlocked yes)
			(layer "F.Fab")
			(hide yes)
			(effects
				(font
					(size 1.016 1.016)
					(thickness 0.1524)
				)
			)
		)
		(property "Device Type" "AAA-PCI-066-K06"
			(at -23.3172 -8.4201 180)
			(unlocked yes)
			(layer "F.Fab")
			(hide yes)
			(effects
				(font
					(size 1.016 1.016)
					(thickness 0.1524)
				)
			)
		)
		(duplicate_pad_numbers_are_jumpers no)
		(pad "" np_thru_hole circle
			(at 0 0 180)
			(size 0.254 0.254)
			(drill 2.3622)
			(layers "*.Cu" "*.Mask")
			(clearance 1.4097)
			(thermal_gap 1.4097)
		)
		(pad "" np_thru_hole circle
			(at 73.14946 0 180)
			(size 0.254 0.254)
			(drill 2.3622)
			(layers "*.Cu" "*.Mask")
			(clearance 1.4097)
			(thermal_gap 1.4097)
		)
		(pad "A1" thru_hole circle
			(at -11.64971 -1.24968 180)
			(size 1.0922 1.0922)
			(drill 0.7366)
			(layers "*.Cu" "*.Mask")
			(remove_unused_layers no)
			(net "PRSNT_MSB_A1")
			(clearance 0.1778)
			(thermal_gap 0.1778)
		)
		(pad "A2" thru_hole circle
			(at -10.65022 -3.24993 180)
			(size 1.0922 1.0922)
			(drill 0.7366)
			(layers "*.Cu" "*.Mask")
			(remove_unused_layers no)
			(net "P12V_MSB")
			(clearance 0.1778)
			(thermal_gap 0.1778)
		)
		(pad "A3" thru_hole circle
			(at -9.64946 -1.24968 180)
			(size 1.0922 1.0922)
			(drill 0.7366)
			(layers "*.Cu" "*.Mask")
			(remove_unused_layers no)
			(net "P12V_MSB")
			(clearance 0.1778)
			(thermal_gap 0.1778)
		)
		(pad "A4" thru_hole circle
			(at -8.64997 -3.24993 180)
			(size 1.0922 1.0922)
			(drill 0.7366)
			(layers "*.Cu" "*.Mask")
			(remove_unused_layers no)
			(net "GND")
			(clearance 0.1778)
			(thermal_gap 0.1778)
		)
		(pad "A5" thru_hole circle
			(at -7.65048 -1.24968 180)
			(size 1.0922 1.0922)
			(drill 0.7366)
			(layers "*.Cu" "*.Mask")
			(remove_unused_layers no)
			(net "SVR_ID0")
			(clearance 0.1778)
			(thermal_gap 0.1778)
		)
		(pad "A6" thru_hole circle
			(at -6.64972 -3.24993 180)
			(size 1.0922 1.0922)
			(drill 0.7366)
			(layers "*.Cu" "*.Mask")
			(remove_unused_layers no)
			(net "SVR_ID1")
			(clearance 0.1778)
			(thermal_gap 0.1778)
		)
		(pad "A7" thru_hole circle
			(at -5.65023 -1.24968 180)
			(size 1.0922 1.0922)
			(drill 0.7366)
			(layers "*.Cu" "*.Mask")
			(remove_unused_layers no)
			(net "CPU_TXD")
			(clearance 0.1778)
			(thermal_gap 0.1778)
		)
		(pad "A8" thru_hole circle
			(at -4.64947 -3.24993 180)
			(size 1.0922 1.0922)
			(drill 0.7366)
			(layers "*.Cu" "*.Mask")
			(remove_unused_layers no)
			(net "CPU_RXD")
			(clearance 0.1778)
			(thermal_gap 0.1778)
		)
		(pad "A9" thru_hole circle
			(at -3.64998 -1.24968 180)
			(size 1.0922 1.0922)
			(drill 0.7366)
			(layers "*.Cu" "*.Mask")
			(remove_unused_layers no)
			(net "SVR_ID2")
			(clearance 0.1778)
			(thermal_gap 0.1778)
		)
		(pad "A10" thru_hole circle
			(at -2.65049 -3.24993 180)
			(size 1.0922 1.0922)
			(drill 0.7366)
			(layers "*.Cu" "*.Mask")
			(remove_unused_layers no)
			(net "SVR_ID3")
			(clearance 0.1778)
			(thermal_gap 0.1778)
		)
		(pad "A11" thru_hole circle
			(at -1.64973 -1.24968 180)
			(size 1.0922 1.0922)
			(drill 0.7366)
			(layers "*.Cu" "*.Mask")
			(remove_unused_layers no)
			(net "PMU_PLTRST#")
			(clearance 0.1778)
			(thermal_gap 0.1778)
		)
		(pad "A12" thru_hole circle
			(at 1.35001 -3.24993 180)
			(size 1.0922 1.0922)
			(drill 0.7366)
			(layers "*.Cu" "*.Mask")
			(remove_unused_layers no)
			(net "GND")
			(clearance 0.1778)
			(thermal_gap 0.1778)
		)
		(pad "A13" thru_hole circle
			(at 2.3495 -1.24968 180)
			(size 1.0922 1.0922)
			(drill 0.7366)
			(layers "*.Cu" "*.Mask")
			(remove_unused_layers no)
			(net "CLK_100M_PCIE_SAS_C_P")
			(clearance 0.1778)
			(thermal_gap 0.1778)
		)
		(pad "A14" thru_hole circle
			(at 3.35026 -3.24993 180)
			(size 1.0922 1.0922)
			(drill 0.7366)
			(layers "*.Cu" "*.Mask")
			(remove_unused_layers no)
			(net "CLK_100M_PCIE_SAS_C_N")
			(clearance 0.1778)
			(thermal_gap 0.1778)
		)
		(pad "A15" thru_hole circle
			(at 4.34975 -1.24968 180)
			(size 1.0922 1.0922)
			(drill 0.7366)
			(layers "*.Cu" "*.Mask")
			(remove_unused_layers no)
			(net "GND")
			(clearance 0.1778)
			(thermal_gap 0.1778)
		)
		(pad "A16" thru_hole circle
			(at 5.35051 -3.24993 180)
			(size 1.0922 1.0922)
			(drill 0.7366)
			(layers "*.Cu" "*.Mask")
			(remove_unused_layers no)
			(net "GND")
			(clearance 0.1778)
			(thermal_gap 0.1778)
		)
		(pad "A17" thru_hole circle
			(at 6.35 -1.24968 180)
			(size 1.0922 1.0922)
			(drill 0.7366)
			(layers "*.Cu" "*.Mask")
			(remove_unused_layers no)
			(net "PCIE_SAS_CPU_RX_P0")
			(clearance 0.1778)
			(thermal_gap 0.1778)
		)
		(pad "A18" thru_hole circle
			(at 7.34949 -3.24993 180)
			(size 1.0922 1.0922)
			(drill 0.7366)
			(layers "*.Cu" "*.Mask")
			(remove_unused_layers no)
			(net "PCIE_SAS_CPU_RX_N0")
			(clearance 0.1778)
			(thermal_gap 0.1778)
		)
		(pad "A19" thru_hole circle
			(at 8.35025 -1.24968 180)
			(size 1.0922 1.0922)
			(drill 0.7366)
			(layers "*.Cu" "*.Mask")
			(remove_unused_layers no)
			(net "GND")
			(clearance 0.1778)
			(thermal_gap 0.1778)
		)
		(pad "A20" thru_hole circle
			(at 9.34974 -3.24993 180)
			(size 1.0922 1.0922)
			(drill 0.7366)
			(layers "*.Cu" "*.Mask")
			(remove_unused_layers no)
			(net "GND")
			(clearance 0.1778)
			(thermal_gap 0.1778)
		)
		(pad "A21" thru_hole circle
			(at 10.3505 -1.24968 180)
			(size 1.0922 1.0922)
			(drill 0.7366)
			(layers "*.Cu" "*.Mask")
			(remove_unused_layers no)
			(net "PCIE_SAS_CPU_RX_P1")
			(clearance 0.1778)
			(thermal_gap 0.1778)
		)
		(pad "A22" thru_hole circle
			(at 11.34999 -3.24993 180)
			(size 1.0922 1.0922)
			(drill 0.7366)
			(layers "*.Cu" "*.Mask")
			(remove_unused_layers no)
			(net "PCIE_SAS_CPU_RX_N1")
			(clearance 0.1778)
			(thermal_gap 0.1778)
		)
		(pad "A23" thru_hole circle
			(at 12.34948 -1.24968 180)
			(size 1.0922 1.0922)
			(drill 0.7366)
			(layers "*.Cu" "*.Mask")
			(remove_unused_layers no)
			(net "GND")
			(clearance 0.1778)
			(thermal_gap 0.1778)
		)
		(pad "A24" thru_hole circle
			(at 13.35024 -3.24993 180)
			(size 1.0922 1.0922)
			(drill 0.7366)
			(layers "*.Cu" "*.Mask")
			(remove_unused_layers no)
			(net "GND")
			(clearance 0.1778)
			(thermal_gap 0.1778)
		)
		(pad "A25" thru_hole circle
			(at 14.34973 -1.24968 180)
			(size 1.0922 1.0922)
			(drill 0.7366)
			(layers "*.Cu" "*.Mask")
			(remove_unused_layers no)
			(net "PCIE_SAS_CPU_RX_P2")
			(clearance 0.1778)
			(thermal_gap 0.1778)
		)
		(pad "A26" thru_hole circle
			(at 15.35049 -3.24993 180)
			(size 1.0922 1.0922)
			(drill 0.7366)
			(layers "*.Cu" "*.Mask")
			(remove_unused_layers no)
			(net "PCIE_SAS_CPU_RX_N2")
			(clearance 0.1778)
			(thermal_gap 0.1778)
		)
		(pad "A27" thru_hole circle
			(at 16.34998 -1.24968 180)
			(size 1.0922 1.0922)
			(drill 0.7366)
			(layers "*.Cu" "*.Mask")
			(remove_unused_layers no)
			(net "GND")
			(clearance 0.1778)
			(thermal_gap 0.1778)
		)
		(pad "A28" thru_hole circle
			(at 17.34947 -3.24993 180)
			(size 1.0922 1.0922)
			(drill 0.7366)
			(layers "*.Cu" "*.Mask")
			(remove_unused_layers no)
			(net "GND")
			(clearance 0.1778)
			(thermal_gap 0.1778)
		)
		(pad "A29" thru_hole circle
			(at 18.35023 -1.24968 180)
			(size 1.0922 1.0922)
			(drill 0.7366)
			(layers "*.Cu" "*.Mask")
			(remove_unused_layers no)
			(net "PCIE_SAS_CPU_RX_P3")
			(clearance 0.1778)
			(thermal_gap 0.1778)
		)
		(pad "A30" thru_hole circle
			(at 19.34972 -3.24993 180)
			(size 1.0922 1.0922)
			(drill 0.7366)
			(layers "*.Cu" "*.Mask")
			(remove_unused_layers no)
			(net "PCIE_SAS_CPU_RX_N3")
			(clearance 0.1778)
			(thermal_gap 0.1778)
		)
		(pad "A31" thru_hole circle
			(at 20.35048 -1.24968 180)
			(size 1.0922 1.0922)
			(drill 0.7366)
			(layers "*.Cu" "*.Mask")
			(remove_unused_layers no)
			(net "GND")
			(clearance 0.1778)
			(thermal_gap 0.1778)
		)
		(pad "A32" thru_hole circle
			(at 21.34997 -3.24993 180)
			(size 1.0922 1.0922)
			(drill 0.7366)
			(layers "*.Cu" "*.Mask")
			(remove_unused_layers no)
			(net "GND")
			(clearance 0.1778)
			(thermal_gap 0.1778)
		)
		(pad "A33" thru_hole circle
			(at 22.34946 -1.24968 180)
			(size 1.0922 1.0922)
			(drill 0.7366)
			(layers "*.Cu" "*.Mask")
			(remove_unused_layers no)
			(net "TP_MSB_A33_CPU_SATA_RX_P")
			(clearance 0.1778)
			(thermal_gap 0.1778)
		)
		(pad "A34" thru_hole circle
			(at 23.35022 -3.24993 180)
			(size 1.0922 1.0922)
			(drill 0.7366)
			(layers "*.Cu" "*.Mask")
			(remove_unused_layers no)
			(net "TP_MSB_A34_CPU_SATA_RX_N")
			(clearance 0.1778)
			(thermal_gap 0.1778)
		)
		(pad "A35" thru_hole circle
			(at 24.34971 -1.24968 180)
			(size 1.0922 1.0922)
			(drill 0.7366)
			(layers "*.Cu" "*.Mask")
			(remove_unused_layers no)
			(net "GND")
			(clearance 0.1778)
			(thermal_gap 0.1778)
		)
		(pad "A36" thru_hole circle
			(at 25.35047 -3.24993 180)
			(size 1.0922 1.0922)
			(drill 0.7366)
			(layers "*.Cu" "*.Mask")
			(remove_unused_layers no)
			(net "GND")
			(clearance 0.1778)
			(thermal_gap 0.1778)
		)
		(pad "A37" thru_hole circle
			(at 26.34996 -1.24968 180)
			(size 1.0922 1.0922)
			(drill 0.7366)
			(layers "*.Cu" "*.Mask")
			(remove_unused_layers no)
			(net "CLK_100M_CLKBUFF_ENET2_DP")
			(clearance 0.1778)
			(thermal_gap 0.1778)
		)
		(pad "A38" thru_hole circle
			(at 27.34945 -3.24993 180)
			(size 1.0922 1.0922)
			(drill 0.7366)
			(layers "*.Cu" "*.Mask")
			(remove_unused_layers no)
			(net "CLK_100M_CLKBUFF_ENET2_DN")
			(clearance 0.1778)
			(thermal_gap 0.1778)
		)
		(pad "A39" thru_hole circle
			(at 28.35021 -1.24968 180)
			(size 1.0922 1.0922)
			(drill 0.7366)
			(layers "*.Cu" "*.Mask")
			(remove_unused_layers no)
			(net "GND")
			(clearance 0.1778)
			(thermal_gap 0.1778)
		)
		(pad "A40" thru_hole circle
			(at 29.3497 -3.24993 180)
			(size 1.0922 1.0922)
			(drill 0.7366)
			(layers "*.Cu" "*.Mask")
			(remove_unused_layers no)
			(net "GND")
			(clearance 0.1778)
			(thermal_gap 0.1778)
		)
		(pad "A41" thru_hole circle
			(at 30.35046 -1.24968 180)
			(size 1.0922 1.0922)
			(drill 0.7366)
			(layers "*.Cu" "*.Mask")
			(remove_unused_layers no)
			(net "TP_MSB_A41")
			(clearance 0.1778)
			(thermal_gap 0.1778)
		)
		(pad "A42" thru_hole circle
			(at 31.34995 -3.24993 180)
			(size 1.0922 1.0922)
			(drill 0.7366)
			(layers "*.Cu" "*.Mask")
			(remove_unused_layers no)
			(net "NIC_SMBUS_ALERT_N")
			(clearance 0.1778)
			(thermal_gap 0.1778)
		)
		(pad "A43" thru_hole circle
			(at 32.34944 -1.24968 180)
			(size 1.0922 1.0922)
			(drill 0.7366)
			(layers "*.Cu" "*.Mask")
			(remove_unused_layers no)
			(net "GND")
			(clearance 0.1778)
			(thermal_gap 0.1778)
		)
		(pad "A44" thru_hole circle
			(at 33.3502 -3.24993 180)
			(size 1.0922 1.0922)
			(drill 0.7366)
			(layers "*.Cu" "*.Mask")
			(remove_unused_layers no)
			(net "GND")
			(clearance 0.1778)
			(thermal_gap 0.1778)
		)
		(pad "A45" thru_hole circle
			(at 34.34969 -1.24968 180)
			(size 1.0922 1.0922)
			(drill 0.7366)
			(layers "*.Cu" "*.Mask")
			(remove_unused_layers no)
			(net "TP_MSB_A45_GBE_RX_P")
			(clearance 0.1778)
			(thermal_gap 0.1778)
		)
		(pad "A46" thru_hole circle
			(at 35.35045 -3.24993 180)
			(size 1.0922 1.0922)
			(drill 0.7366)
			(layers "*.Cu" "*.Mask")
			(remove_unused_layers no)
			(net "TP_MSB_A46_GBE_RX_N")
			(clearance 0.1778)
			(thermal_gap 0.1778)
		)
		(pad "A47" thru_hole circle
			(at 36.34994 -1.24968 180)
			(size 1.0922 1.0922)
			(drill 0.7366)
			(layers "*.Cu" "*.Mask")
			(remove_unused_layers no)
			(net "GND")
			(clearance 0.1778)
			(thermal_gap 0.1778)
		)
		(pad "A48" thru_hole circle
			(at 37.34943 -3.24993 180)
			(size 1.0922 1.0922)
			(drill 0.7366)
			(layers "*.Cu" "*.Mask")
			(remove_unused_layers no)
			(net "GND")
			(clearance 0.1778)
			(thermal_gap 0.1778)
		)
		(pad "A49" thru_hole circle
			(at 38.35019 -1.24968 180)
			(size 1.0922 1.0922)
			(drill 0.7366)
			(layers "*.Cu" "*.Mask")
			(remove_unused_layers no)
			(net "PCIE_SAS_CPU_RX_P4")
			(clearance 0.1778)
			(thermal_gap 0.1778)
		)
		(pad "A50" thru_hole circle
			(at 39.34968 -3.24993 180)
			(size 1.0922 1.0922)
			(drill 0.7366)
			(layers "*.Cu" "*.Mask")
			(remove_unused_layers no)
			(net "PCIE_SAS_CPU_RX_N4")
			(clearance 0.1778)
			(thermal_gap 0.1778)
		)
		(pad "A51" thru_hole circle
			(at 40.35044 -1.24968 180)
			(size 1.0922 1.0922)
			(drill 0.7366)
			(layers "*.Cu" "*.Mask")
			(remove_unused_layers no)
			(net "GND")
			(clearance 0.1778)
			(thermal_gap 0.1778)
		)
		(pad "A52" thru_hole circle
			(at 41.34993 -3.24993 180)
			(size 1.0922 1.0922)
			(drill 0.7366)
			(layers "*.Cu" "*.Mask")
			(remove_unused_layers no)
			(net "GND")
			(clearance 0.1778)
			(thermal_gap 0.1778)
		)
		(pad "A53" thru_hole circle
			(at 42.34942 -1.24968 180)
			(size 1.0922 1.0922)
			(drill 0.7366)
			(layers "*.Cu" "*.Mask")
			(remove_unused_layers no)
			(net "PCIE_SAS_CPU_RX_P5")
			(clearance 0.1778)
			(thermal_gap 0.1778)
		)
		(pad "A54" thru_hole circle
			(at 43.35018 -3.24993 180)
			(size 1.0922 1.0922)
			(drill 0.7366)
			(layers "*.Cu" "*.Mask")
			(remove_unused_layers no)
			(net "PCIE_SAS_CPU_RX_N5")
			(clearance 0.1778)
			(thermal_gap 0.1778)
		)
		(pad "A55" thru_hole circle
			(at 44.34967 -1.24968 180)
			(size 1.0922 1.0922)
			(drill 0.7366)
			(layers "*.Cu" "*.Mask")
			(remove_unused_layers no)
			(net "GND")
			(clearance 0.1778)
			(thermal_gap 0.1778)
		)
		(pad "A56" thru_hole circle
			(at 45.35043 -3.24993 180)
			(size 1.0922 1.0922)
			(drill 0.7366)
			(layers "*.Cu" "*.Mask")
			(remove_unused_layers no)
			(net "GND")
			(clearance 0.1778)
			(thermal_gap 0.1778)
		)
		(pad "A57" thru_hole circle
			(at 46.34992 -1.24968 180)
			(size 1.0922 1.0922)
			(drill 0.7366)
			(layers "*.Cu" "*.Mask")
			(remove_unused_layers no)
			(net "PCIE_SAS_CPU_RX_P6")
			(clearance 0.1778)
			(thermal_gap 0.1778)
		)
		(pad "A58" thru_hole circle
			(at 47.34941 -3.24993 180)
			(size 1.0922 1.0922)
			(drill 0.7366)
			(layers "*.Cu" "*.Mask")
			(remove_unused_layers no)
			(net "PCIE_SAS_CPU_RX_N6")
			(clearance 0.1778)
			(thermal_gap 0.1778)
		)
		(pad "A59" thru_hole circle
			(at 48.35017 -1.24968 180)
			(size 1.0922 1.0922)
			(drill 0.7366)
			(layers "*.Cu" "*.Mask")
			(remove_unused_layers no)
			(net "GND")
			(clearance 0.1778)
			(thermal_gap 0.1778)
		)
		(pad "A60" thru_hole circle
			(at 49.34966 -3.24993 180)
			(size 1.0922 1.0922)
			(drill 0.7366)
			(layers "*.Cu" "*.Mask")
			(remove_unused_layers no)
			(net "GND")
			(clearance 0.1778)
			(thermal_gap 0.1778)
		)
		(pad "A61" thru_hole circle
			(at 50.35042 -1.24968 180)
			(size 1.0922 1.0922)
			(drill 0.7366)
			(layers "*.Cu" "*.Mask")
			(remove_unused_layers no)
			(net "PCIE_SAS_CPU_RX_P7")
			(clearance 0.1778)
			(thermal_gap 0.1778)
		)
		(pad "A62" thru_hole circle
			(at 51.34991 -3.24993 180)
			(size 1.0922 1.0922)
			(drill 0.7366)
			(layers "*.Cu" "*.Mask")
			(remove_unused_layers no)
			(net "PCIE_SAS_CPU_RX_N7")
			(clearance 0.1778)
			(thermal_gap 0.1778)
		)
		(pad "A63" thru_hole circle
			(at 52.3494 -1.24968 180)
			(size 1.0922 1.0922)
			(drill 0.7366)
			(layers "*.Cu" "*.Mask")
			(remove_unused_layers no)
			(net "GND")
			(clearance 0.1778)
			(thermal_gap 0.1778)
		)
		(pad "A64" thru_hole circle
			(at 53.35016 -3.24993 180)
			(size 1.0922 1.0922)
			(drill 0.7366)
			(layers "*.Cu" "*.Mask")
			(remove_unused_layers no)
			(net "GND")
			(clearance 0.1778)
			(thermal_gap 0.1778)
		)
		(pad "A65" thru_hole circle
			(at 54.34965 -1.24968 180)
			(size 1.0922 1.0922)
			(drill 0.7366)
			(layers "*.Cu" "*.Mask")
			(remove_unused_layers no)
			(net "PCIE_10G_CPU_RX0_P")
			(clearance 0.1778)
			(thermal_gap 0.1778)
		)
		(pad "A66" thru_hole circle
			(at 55.35041 -3.24993 180)
			(size 1.0922 1.0922)
			(drill 0.7366)
			(layers "*.Cu" "*.Mask")
			(remove_unused_layers no)
			(net "PCIE_10G_CPU_RX0_N")
			(clearance 0.1778)
			(thermal_gap 0.1778)
		)
		(pad "A67" thru_hole circle
			(at 56.3499 -1.24968 180)
			(size 1.0922 1.0922)
			(drill 0.7366)
			(layers "*.Cu" "*.Mask")
			(remove_unused_layers no)
			(net "GND")
			(clearance 0.1778)
			(thermal_gap 0.1778)
		)
		(pad "A68" thru_hole circle
			(at 57.34939 -3.24993 180)
			(size 1.0922 1.0922)
			(drill 0.7366)
			(layers "*.Cu" "*.Mask")
			(remove_unused_layers no)
			(net "GND")
			(clearance 0.1778)
			(thermal_gap 0.1778)
		)
		(pad "A69" thru_hole circle
			(at 58.35015 -1.24968 180)
			(size 1.0922 1.0922)
			(drill 0.7366)
			(layers "*.Cu" "*.Mask")
			(remove_unused_layers no)
			(net "PCIE_10G_CPU_RX1_P")
			(clearance 0.1778)
			(thermal_gap 0.1778)
		)
		(pad "A70" thru_hole circle
			(at 59.34964 -3.24993 180)
			(size 1.0922 1.0922)
			(drill 0.7366)
			(layers "*.Cu" "*.Mask")
			(remove_unused_layers no)
			(net "PCIE_10G_CPU_RX1_N")
			(clearance 0.1778)
			(thermal_gap 0.1778)
		)
		(pad "A71" thru_hole circle
			(at 60.3504 -1.24968 180)
			(size 1.0922 1.0922)
			(drill 0.7366)
			(layers "*.Cu" "*.Mask")
			(remove_unused_layers no)
			(net "GND")
			(clearance 0.1778)
			(thermal_gap 0.1778)
		)
		(pad "A72" thru_hole circle
			(at 61.34989 -3.24993 180)
			(size 1.0922 1.0922)
			(drill 0.7366)
			(layers "*.Cu" "*.Mask")
			(remove_unused_layers no)
			(net "GND")
			(clearance 0.1778)
			(thermal_gap 0.1778)
		)
		(pad "A73" thru_hole circle
			(at 62.34938 -1.24968 180)
			(size 1.0922 1.0922)
			(drill 0.7366)
			(layers "*.Cu" "*.Mask")
			(remove_unused_layers no)
			(net "PCIE_10G_CPU_RX2_P")
			(clearance 0.1778)
			(thermal_gap 0.1778)
		)
	)
)
